FILE_TYPE = CONNECTIVITY;
{Allegro Design Entry HDL 16.6-p007 (v16-6-112F) 10/10/2012}
"PAGE_NUMBER" = 215;
0"NC";
1"PVCCIO_CPU0\g";
2"P3V3_STBY\g";
3"GND\g";
4"GND\g";
5"GND\g";
6"GND\g";
7"P3V3_STBY\g";
8"GND\g";
9"GND\g";
10"GND\g";
11"GND\g";
12"GND\g";
13"GND\g";
14"PVCCIO_CPU0\g";
15"VR_FET_SW_P12V_STBY_PVDDQ_ABC\g";
16"GND\g";
17"GND\g";
18"GND\g";
19"VR_PVDDQ_ABC_VINSEN";
20"SVID_CLK1_CPU0_R";
21"SVID_DIO1_CPU0_R";
22"PWRGD_PVDDQ_ABC";
23"IRQ_PVDDQ_ABC_VRHOT_LVT3_N";
24"SVID_ALERT1_CPU0_R_N";
25"SMB_VR_STBY_LVC3_SCL";
26"SMB_VR_STBY_LVC3_SDA";
27"VR_PVDDQ_ABC_VD12";
28"VR_PVDDQ_ABC_PWM1";
29"VR_PVDDQ_ABC_PWM2";
30"PWRGD_PVDDQ_ABC_R";
31"PU_VR_PVDDQ_ABC_FAULT1";
32"SMB_VR_SCL_VDDQ_ABC";
33"IRQ_PVDDQ_ABC_VRHOT_LVT3_R_N";
34"TP_PVDDQ_ABC_MP2";
35"TP_PVDDQ_ABC_PINALRT_N";
36"SMB_VR_SDA_VDDQ_ABC";
37"SVID_ALERT_PVDDQ_ABC";
38"VR_PVDDQ_ABC_VD12";
39"TP_PVDDQ_ABC_BPWM1";
40"TP_PVDDQ_ABC_PWM3";
41"SVID_VDIO_PVDDQ_ABC";
42"NC_PVDDQ_ABC_DNC0";
43"NC_PVDDQ_ABC_DNC1";
44"TP_PVDDQ_ABC_MP1";
45"VR_PVDDQ_ABC_VDD";
46"SVID_CLK_PVDDQ_ABC";
47"TP_PVDDQ_ABC_PH3_IMON";
48"TP_PVDDQ_ABC_PH3_IMON_REF";
49"VR_PVDDQ_ABC_VREN";
50"A_TSENSE_PVDDQ_ABC";
51"VR_PVDDQ_ABC_XADDR2";
52"TP_PVDDQ_ABC_RESET_N";
53"VR_PVDDQ_ABC_XADDR1";
54"TP_PVDDQ_ABC_BTSEN";
55"TP_PVDDQ_ABC_BREF1";
56"TP_PVDDQ_ABC_BVSEN";
57"TP_PVDDQ_ABC_BVREF";
58"VSENSE_PVDDQ_ABC_N";
59"VR_PVDDQ_ABC_AVSP";
60"VR_PVDDQ_ABC_AIREF1";
61"VR_PVDDQ_ABC_AIREF2";
62"VR_PVDDQ_ABC_AIINSEN";
63"ISENSE_PVDDQ_ABC_PH1_IMON";
64"ISENSE_PVDDQ_ABC_PH2_IMON";
65"VR_PVDDQ_ABC_VINSEN";
66"VR_PVDDQ_ABC_VD12";
67"FM_PVDDQ_ABC_EN";
68"VSENSE_PVDDQ_ABC_P";
%"PVCCIO_CPU0"
"1","(4100,3150)","0","mstr_symbols","I294";
;
HDL_POWER"PVCCIO_CPU0"
CDS_LIB"mstr_symbols"
VOLTAGE"1.1V"
BODY_TYPE"PLUMBING";
"G\NAC"1;
%"RES"
"2","(4100,2925)","0","mstr_discrete","I295";
;
CDS_SEC"1"
ROOM"VDDQ_ABC_PWR_VR"
SEC"1"
SEC_TYPE"0402"
CDS_LOCATION"R3U2"
CDS_LIB"mstr_discrete"
LOCATION"R3U2"
PART_NUMBER"G21796-017"
MATERIAL"CHIP"
TOLERANCE"1%"
VALUE"100.0"
WATTAGE"1/16W"
PACK_TYPE"0402";
"A"
$PN"1"1;
"B"
$PN"2"21;
%"RES"
"1","(3500,2650)","0","mstr_discrete","I296";
;
CDS_SEC"1"
SEC_TYPE"0402"
SEC"1"
CDS_LIB"mstr_discrete"
CDS_LOCATION"R7F24"
ROOM"VDDQ_ABC_PWR_VR"
LOCATION"R7F24"
PART_NUMBER"G21796-250"
TOLERANCE"1.0%"
MATERIAL"CHIP"
WATTAGE"1/16W"
VALUE"22.1"
PACK_TYPE"0402";
"B"
$PN"2"22;
"A"
$PN"1"30;
%"RES"
"1","(3425,2550)","0","mstr_discrete","I297";
;
CDS_SEC"1"
$SEC"1"
CDS_LOCATION"R7F23"
CDS_LIB"mstr_discrete"
PACK_TYPE"0402"
PART_NUMBER"G21796-074"
LOCATION"R7F23"
TOLERANCE"1%"
MATERIAL"CHIP"
VALUE"33.2"
WATTAGE"1/16W";
"B"
$PN"2"23;
"A"
$PN"1"33;
%"RES"
"1","(3400,2150)","0","mstr_discrete","I298";
;
$SEC"1"
CDS_SEC"1"
ROOM"VDDQ_ABC_PWR_VR"
CDS_LIB"mstr_discrete"
CDS_LOCATION"R7F25"
PART_NUMBER"G21796-173"
LOCATION"R7F25"
TOLERANCE"1%"
VALUE"20.0"
PACK_TYPE"0402"
MATERIAL"CHIP"
WATTAGE"1/16W";
"B"
$PN"2"25;
"A"
$PN"1"32;
%"P3V3_STBY"
"1","(2950,3875)","0","mstr_symbols","I299";
;
CDS_LIB"mstr_symbols"
SIZE"1B"
VOLTAGE"3.3V"
BODY_TYPE"PLUMBING"
HDL_POWER"P3V3_STBY";
"G\NAC"2;
%"RES"
"2","(3075,3050)","0","mstr_discrete","I300";
;
CDS_SEC"1"
CDS_LOCATION"R7F36"
SEC_TYPE"0402"
SEC"1"
CDS_LIB"mstr_discrete"
ROOM"VDDQ_ABC_PWR_VR"
VALUE"2.26K"
LOCATION"R7F36"
TOLERANCE"1.0%"
PART_NUMBER"G21796-311"
MATERIAL"EMPTY"
PACK_TYPE"0402"
WATTAGE"1/16W";
"A"
$PN"1"2;
"B"
$PN"2"31;
%"RES"
"2","(2750,3200)","0","mstr_discrete","I301";
;
CDS_SEC"1"
ROOM"VDDQ_ABC_PWR_VR"
SEC_TYPE"0402"
SEC"1"
CDS_LOCATION"R7F22"
CDS_LIB"mstr_discrete"
PART_NUMBER"G21796-026"
LOCATION"R7F22"
VALUE"1.00K"
TOLERANCE"1%"
MATERIAL"CHIP"
WATTAGE"1/16W"
PACK_TYPE"0402";
"A"
$PN"1"2;
"B"
$PN"2"30;
%"RES"
"1","(2925,2500)","0","mstr_discrete","I302";
;
CDS_SEC"1"
SEC_TYPE"0402"
SEC"1"
ROOM"VDDQ_ABC_PWR_VR"
CDS_LOCATION"R7G4"
CDS_LIB"mstr_discrete"
MATERIAL"CHIP"
PACK_TYPE"0402"
LOCATION"R7G4"
TOLERANCE"5%"
PART_NUMBER"G21497-005"
VALUE"0.0"
WATTAGE"1/16W";
"B"
$PN"2"24;
"A"
$PN"1"37;
%"RES"
"2","(2400,3200)","0","mstr_discrete","I303";
;
CDS_SEC"1"
ROOM"VDDQ_ABC_PWR_VR"
SEC"1"
SEC_TYPE"0402"
CDS_LOCATION"R7F27"
CDS_LIB"mstr_discrete"
LOCATION"R7F27"
PART_NUMBER"G21796-026"
VALUE"1.00K"
WATTAGE"1/16W"
MATERIAL"CHIP"
TOLERANCE"1%"
PACK_TYPE"0402";
"A"
$PN"1"2;
"B"
$PN"2"33;
%"RES"
"1","(3075,2100)","0","mstr_discrete","I304";
;
CDS_LIB"mstr_discrete"
CDS_SEC"1"
$SEC"1"
CDS_LOCATION"R7F26"
ROOM"VDDQ_ABC_PWR_VR"
LOCATION"R7F26"
PART_NUMBER"G21796-173"
TOLERANCE"1%"
PACK_TYPE"0402"
MATERIAL"CHIP"
VALUE"20.0"
WATTAGE"1/16W";
"B"
$PN"2"26;
"A"
$PN"1"36;
%"CAP"
"1","(3225,1350)","0","mstr_discrete","I305";
;
CDS_SEC"1"
SEC_TYPE"0402LF"
SEC"1"
ROOM"VDDQ_ABC_PWR_VR"
CDS_LIB"mstr_discrete"
CDS_LOCATION"C7F14"
LOCATION"C7F14"
PART_NUMBER"A36096-046"
VALUE"1000PF"
TOLERANCE"10%"
PACK_TYPE"0402LF"
VOLTAGE"50V"
MATERIAL"X7R";
"A"
$PN"1"30;
"B"
$PN"2"3;
%"GND"
"1","(3225,1075)","0","mstr_symbols","I306";
;
HDL_POWER"GND"
VOLTAGE"0"
SIZE"1B"
CDS_LIB"mstr_symbols"
BODY_TYPE"PLUMBING"
ROOM"VDDQ_ABC_PWR_VR";
"A\NAC"3;
%"RES"
"1","(3075,1800)","0","mstr_discrete","I307";
;
CDS_SEC"1"
CDS_LIB"mstr_discrete"
ROOM"VDDQ_ABC_PWR_VR"
CDS_LOCATION"R7G2"
SEC"1"
SEC_TYPE"0402"
PACK_TYPE"0402"
MATERIAL"CHIP"
LOCATION"R7G2"
PART_NUMBER"G21497-005"
TOLERANCE"5%"
VALUE"0.0"
WATTAGE"1/16W";
"B"
$PN"2"21;
"A"
$PN"1"41;
%"GND"
"1","(2300,925)","0","mstr_symbols","I308";
;
HDL_POWER"GND"
VOLTAGE"0"
SIZE"1B"
CDS_LIB"mstr_symbols"
BODY_TYPE"PLUMBING"
ROOM"VDDQ_ABC_PWR_VR";
"A\NAC"4;
%"CAP_A"
"1","(1825,3200)","0","dev_discrete","I309";
;
ROOM"VDDQ_ABC_PWR_VR"
CDS_SEC"1"
$SEC"1"
CDS_LOCATION"C7F18"
CDS_LIB"dev_discrete"
PART_NUMBER"D97712-004"
VOLTAGE"6.3V"
MATERIAL"X6S"
TOLERANCE"10%"
VALUE"1.0UF"
LOCATION"C7F18"
PACK_TYPE"0402V";
"B"
$PN"2"5;
"A"
$PN"1"45;
%"GND"
"1","(1825,3000)","0","mstr_symbols","I310";
;
HDL_POWER"GND"
ROOM"VDDQ_ABC_PWR_VR"
BODY_TYPE"PLUMBING"
CDS_LIB"mstr_symbols"
SIZE"1B"
VOLTAGE"0";
"A\NAC"5;
%"CAP_A"
"1","(1425,3200)","0","dev_discrete","I311";
;
SEC"1"
SEC_TYPE"0402V"
CDS_SEC"1"
ROOM"VDDQ_ABC_PWR_VR"
CDS_LIB"dev_discrete"
CDS_LOCATION"C7F17"
LOCATION"C7F17"
VALUE"0.1UF"
TOLERANCE"10%"
VOLTAGE"16V"
MATERIAL"X7R"
PART_NUMBER"A36096-030"
PACK_TYPE"0402V";
"B"
$PN"2"6;
"A"
$PN"1"45;
%"GND"
"1","(1425,3000)","0","mstr_symbols","I312";
;
HDL_POWER"GND"
VOLTAGE"0"
SIZE"1B"
CDS_LIB"mstr_symbols"
BODY_TYPE"PLUMBING"
ROOM"VDDQ_ABC_PWR_VR";
"A\NAC"6;
%"RES"
"2","(1125,3550)","0","mstr_discrete","I313";
;
CDS_SEC"1"
SEC_TYPE"0402"
SEC"1"
CDS_LOCATION"R3T13"
ROOM"VDDQ_ABC_PWR_VR"
CDS_LIB"mstr_discrete"
LOCATION"R3T13"
VALUE"0.0"
TOLERANCE"5%"
PART_NUMBER"G21497-005"
PACK_TYPE"0402"
MATERIAL"CHIP"
WATTAGE"1/16W";
"A"
$PN"1"7;
"B"
$PN"2"45;
%"P3V3_STBY"
"1","(1125,3975)","0","mstr_symbols","I314";
;
SIZE"1B"
CDS_LIB"mstr_symbols"
VOLTAGE"3.3V"
BODY_TYPE"PLUMBING"
HDL_POWER"P3V3_STBY";
"G\NAC"7;
%"RES"
"2","(425,3625)","0","mstr_discrete","I315";
;
BOM_COST"SM_CONTROLLER"
CDS_SEC"1"
$SEC"1"
ROOM"BMC"
CDS_LOCATION"R7F20"
CDS_LIB"mstr_discrete"
MATERIAL"EMPTY"
LOCATION"R7F20"
PART_NUMBER"G21796-010"
VALUE"100.0K"
TOLERANCE"1%"
PACK_TYPE"0402"
WATTAGE"1/16W";
"A"
$PN"1"7;
"B"
$PN"2"49;
%"RES"
"2","(850,400)","0","mstr_discrete","I317";
;
CDS_SEC"1"
$SEC"1"
CDS_LOCATION"R7G10"
ROOM"VDDQ_ABC_PWR_VR"
CDS_LIB"mstr_discrete"
LOCATION"R7G10"
PART_NUMBER"G21796-078"
VALUE"8.06K"
WATTAGE"1/16W"
TOLERANCE"1%"
MATERIAL"CHIP"
PACK_TYPE"0402";
"A"
$PN"1"51;
"B"
$PN"2"8;
%"GND"
"1","(850,150)","0","mstr_symbols","I318";
;
HDL_POWER"GND"
VOLTAGE"0"
CDS_LIB"mstr_symbols"
SIZE"1B"
BODY_TYPE"PLUMBING"
ROOM"VDDQ_ABC_PWR_VR";
"A\NAC"8;
%"GND"
"1","(400,950)","0","mstr_symbols","I319";
;
HDL_POWER"GND"
VOLTAGE"0"
CDS_LIB"mstr_symbols"
SIZE"1B"
BODY_TYPE"PLUMBING"
ROOM"VDDQ_ABC_PWR_VR";
"A\NAC"9;
%"CAP"
"1","(325,850)","2","mstr_discrete","I320";
;
CDS_SEC"1"
SEC_TYPE"0402LF"
SEC"1"
ROOM"VDDQ_ABC_PWR_VR"
CDS_LOCATION"C7G3"
CDS_LIB"mstr_discrete"
VALUE"220PF"
LOCATION"C7G3"
PACK_TYPE"0402LF"
VOLTAGE"50V"
MATERIAL"X7R"
TOLERANCE"10%"
PART_NUMBER"A36096-050";
"A"
$PN"1"50;
"B"
$PN"2"11;
%"RES"
"2","(500,400)","0","mstr_discrete","I321";
;
CDS_SEC"1"
$SEC"1"
CDS_LOCATION"R7G8"
ROOM"VDDQ_ABC_PWR_VR"
CDS_LIB"mstr_discrete"
LOCATION"R7G8"
PART_NUMBER"G21796-082"
VALUE"4.02K"
TOLERANCE"1%"
PACK_TYPE"0402"
MATERIAL"CHIP"
WATTAGE"1/16W";
"A"
$PN"1"53;
"B"
$PN"2"10;
%"GND"
"1","(500,150)","0","mstr_symbols","I322";
;
SIZE"1B"
HDL_POWER"GND"
VOLTAGE"0"
CDS_LIB"mstr_symbols"
BODY_TYPE"PLUMBING"
ROOM"VDDQ_ABC_PWR_VR";
"A\NAC"10;
%"GND"
"1","(325,150)","0","mstr_symbols","I323";
;
HDL_POWER"GND"
SIZE"1B"
BODY_TYPE"PLUMBING"
CDS_LIB"mstr_symbols"
VOLTAGE"0"
ROOM"VDDQ_ABC_PWR_VR";
"A\NAC"11;
%"CAP_A"
"1","(3000,500)","0","dev_discrete","I325";
;
ROOM"VDDQ_ABC_PWR_VR"
SEC"1"
SEC_TYPE"0402V"
CDS_SEC"1"
CDS_LOCATION"C7F16"
CDS_LIB"dev_discrete"
LOCATION"C7F16"
PART_NUMBER"D97712-004"
VALUE"1.0UF"
TOLERANCE"10%"
PACK_TYPE"0402V"
VOLTAGE"6.3V"
MATERIAL"X6S";
"B"
$PN"2"12;
"A"
$PN"1"38;
%"GND"
"1","(3000,225)","0","mstr_symbols","I326";
;
SIZE"1B"
HDL_POWER"GND"
CDS_LIB"mstr_symbols"
VOLTAGE"0"
BODY_TYPE"PLUMBING"
ROOM"VDDQ_ABC_PWR_VR";
"A\NAC"12;
%"CAP_A"
"1","(2600,500)","0","dev_discrete","I327";
;
SEC"1"
SEC_TYPE"0402V"
CDS_SEC"1"
CDS_LOCATION"C7F15"
ROOM"VDDQ_ABC_PWR_VR"
CDS_LIB"dev_discrete"
VALUE"0.1UF"
LOCATION"C7F15"
VOLTAGE"16V"
PART_NUMBER"A36096-030"
TOLERANCE"10%"
PACK_TYPE"0402V"
MATERIAL"X7R";
"B"
$PN"2"13;
"A"
$PN"1"38;
%"GND"
"1","(2600,300)","0","mstr_symbols","I328";
;
HDL_POWER"GND"
CDS_LIB"mstr_symbols"
VOLTAGE"0"
SIZE"1B"
BODY_TYPE"PLUMBING"
ROOM"VDDQ_ABC_PWR_VR";
"A\NAC"13;
%"PVCCIO_CPU0"
"1","(-100,3900)","0","mstr_symbols","I329";
;
VOLTAGE"1.1V"
CDS_LIB"mstr_symbols"
BODY_TYPE"PLUMBING"
HDL_POWER"PVCCIO_CPU0";
"G\NAC"14;
%"RES"
"2","(-100,3625)","0","mstr_discrete","I330";
;
CDS_SEC"1"
SEC_TYPE"0402"
SEC"1"
ROOM"VDDQ_ABC_PWR_VR"
CDS_LOCATION"R3T11"
CDS_LIB"mstr_discrete"
MATERIAL"EMPTY"
LOCATION"R3T11"
PART_NUMBER"G21796-047"
VALUE"49.9"
TOLERANCE"1%"
PACK_TYPE"0402"
WATTAGE"1/16W";
"A"
$PN"1"14;
"B"
$PN"2"20;
%"RES"
"1","(125,3100)","0","mstr_discrete","I331";
;
CDS_SEC"1"
CDS_LOCATION"R7G24"
ROOM"VDDQ_ABC_PWR_VR"
SEC"1"
SEC_TYPE"0402"
CDS_LIB"mstr_discrete"
PACK_TYPE"0402"
PART_NUMBER"G21796-009"
MATERIAL"CHIP"
TOLERANCE"1%"
LOCATION"R7G24"
WATTAGE"1/16W"
VALUE"150.0";
"B"
$PN"2"46;
"A"
$PN"1"20;
%"RES"
"1","(-300,2925)","0","mstr_discrete","I332";
;
CDS_SEC"1"
$SEC"1"
ROOM"PVCCIN_CPU0_VR"
CDS_LOCATION"R3U3"
CDS_LIB"mstr_discrete"
PACK_TYPE"0402"
PART_NUMBER"G21497-005"
LOCATION"R3U3"
MATERIAL"CHIP"
WATTAGE"1/16W"
VALUE"0.0"
TOLERANCE"5%";
"B"
$PN"2"61;
"A"
$PN"1"66;
%"VCC_CORE"
"1","(-950,4000)","0","mstr_symbols","I335";
;
CDS_LIB"mstr_symbols"
HDL_POWER"VR_FET_SW_P12V_STBY_PVDDQ_ABC";
"A"15;
%"RES"
"2","(-950,3775)","0","mstr_discrete","I336";
;
CDS_SEC"1"
SEC_TYPE"0402"
SEC"1"
ROOM"VDDQ_ABC_PWR_VR"
CDS_LOCATION"R7F34"
CDS_LIB"mstr_discrete"
LOCATION"R7F34"
PART_NUMBER"G21796-160"
VALUE"100.0K"
WATTAGE"1/16W"
MATERIAL"CHIP"
PACK_TYPE"0402"
TOLERANCE"1%";
"A"
$PN"1"15;
"B"
$PN"2"19;
%"RES"
"2","(-950,3400)","0","mstr_discrete","I337";
;
CDS_SEC"1"
SEC"1"
SEC_TYPE"0402"
ROOM"VDDQ_ABC_PWR_VR"
CDS_LOCATION"R7G3"
CDS_LIB"mstr_discrete"
PART_NUMBER"G21796-003"
WATTAGE"1/16W"
TOLERANCE"1%"
VALUE"1.5K"
LOCATION"R7G3"
MATERIAL"CHIP"
PACK_TYPE"0402";
"A"
$PN"1"19;
"B"
$PN"2"16;
%"GND"
"1","(-950,3150)","0","mstr_symbols","I338";
;
HDL_POWER"GND"
SIZE"1B"
BODY_TYPE"PLUMBING"
CDS_LIB"mstr_symbols"
VOLTAGE"0"
ROOM"VDDQ_ABC_PWR_VR";
"A\NAC"16;
%"CAP"
"1","(-1175,3400)","2","mstr_discrete","I339";
;
CDS_SEC"1"
SEC_TYPE"0402LF"
SEC"1"
ROOM"VDDQ_ABC_PWR_VR"
CDS_LIB"mstr_discrete"
CDS_LOCATION"C7G1"
LOCATION"C7G1"
VALUE"1000PF"
VOLTAGE"50V"
TOLERANCE"10%"
MATERIAL"X7R"
PART_NUMBER"A36096-046"
PACK_TYPE"0402LF";
"A"
$PN"1"19;
"B"
$PN"2"17;
%"GND"
"1","(-1175,3150)","0","mstr_symbols","I340";
;
HDL_POWER"GND"
SIZE"1B"
BODY_TYPE"PLUMBING"
CDS_LIB"mstr_symbols"
VOLTAGE"0"
ROOM"VDDQ_ABC_PWR_VR";
"A\NAC"17;
%"RES"
"1","(-1225,2775)","0","mstr_discrete","I341";
;
CDS_LOCATION"R3U10"
ROOM"PVCCIN_CPU0_VR"
CDS_SEC"1"
$SEC"1"
CDS_LIB"mstr_discrete"
LOCATION"R3U10"
TOLERANCE"5%"
PACK_TYPE"0402"
MATERIAL"CHIP"
PART_NUMBER"G21497-005"
WATTAGE"1/16W"
VALUE"0.0";
"B"
$PN"2"60;
"A"
$PN"1"66;
%"CAP"
"1","(-850,1150)","0","mstr_discrete","I342";
;
CDS_SEC"1"
ROOM"VDDQ_ABC_PWR_VR"
SEC"1"
SEC_TYPE"0402LF"
NO_XNET_CONNECTION"1"
CDS_LIB"mstr_discrete"
CDS_LOCATION"C7G4"
PART_NUMBER"A36096-050"
MATERIAL"X7R"
TOLERANCE"10%"
LOCATION"C7G4"
VALUE"220PF"
PACK_TYPE"0402LF"
VOLTAGE"50V";
"A"
$PN"1"59;
"B"
$PN"2"58;
%"RES"
"1","(-975,1600)","0","mstr_discrete","I343";
;
CDS_LIB"mstr_discrete"
CDS_SEC"1"
$SEC"1"
CDS_LOCATION"R7F21"
ROOM"PVCCIN_CPU0_VR"
PACK_TYPE"0402"
MATERIAL"CHIP"
LOCATION"R7F21"
PART_NUMBER"G21497-005"
TOLERANCE"5%"
WATTAGE"1/16W"
VALUE"0.0";
"B"
$PN"2"49;
"A"
$PN"1"67;
%"RES"
"1","(-1125,1325)","0","mstr_discrete","I344";
;
CDS_SEC"1"
NO_XNET_CONNECTION"1"
SEC"1"
SEC_TYPE"0402"
ROOM"VDDQ_ABC_PWR_VR"
CDS_LIB"mstr_discrete"
CDS_LOCATION"R7G9"
PART_NUMBER"G21796-066"
PACK_TYPE"0402"
MATERIAL"CHIP"
LOCATION"R7G9"
WATTAGE"1/16W"
TOLERANCE"1%"
VALUE"10.0";
"B"
$PN"2"59;
"A"
$PN"1"68;
%"PXM1310B"
"2","(1725,1900)","0","mstr_controller","I358";
;
CDS_LOCATION"EU7G1"
$SEC"1"
CDS_SEC"1"
PACK_TYPE"QFN"
CDS_LIB"mstr_controller"
CDS_LMAN_SYM_OUTLINE"-400,900,400,-900"
LOCATION"EU7G1"
MATERIAL"IC"
PART_NUMBER"H89186-001";
"MP2"
$PN"18"34;
"MP1"
$PN"14"44;
"MP0"
$PN"13"31;
"AVREN"
$PN"10"49;
"AVRRDY"
$PN"9"30;
"IINSEN"
$PN"38"62;
"GND"
$PN"27"4;
"VD12"
$PN"40"27;
"VINSEN"
$PN"37"65;
"BVREF"
$PN"30"57;
"BVSEN"
$PN"29"56;
"AVREF"
$PN"20"58;
"AVSEN"
$PN"19"59;
"VALRT_N \B"
$PN"17"37;
"PINALRT_N \B"
$PN"12"35;
"VRHOT_N \B"
$PN"11"33;
"DNC<1>"
$PN"28"43;
"DNC<0>"
$PN"2"42;
"BIREF1"
$PN"31"55;
"BISEN1"
$PN"32"9;
"BTSEN"
$PN"34"54;
"VDD"
$PN"39"45;
"AIREF1"
$PN"21"60;
"AISEN1"
$PN"22"63;
"ATSEN"
$PN"35"50;
"AIREF2"
$PN"23"61;
"AISEN2"
$PN"24"64;
"XADDR2"
$PN"33"51;
"AIREF3"
$PN"25"48;
"AISEN3"
$PN"26"47;
"XADDR1"
$PN"36"53;
"RESET_N \B"
$PN"8"52;
"VDIO"
$PN"16"41;
"VCLK"
$PN"15"46;
"SCL"
$PN"7"32;
"SDA"
$PN"6"36;
"APWM3"
$PN"3"40;
"APWM2"
$PN"4"29;
"APWM1"
$PN"5"28;
"BPWM1"
$PN"1"39;
"THPAD"
$PN"41"4;
%"GND"
"1","(-75,150)","0","mstr_symbols","I359";
;
SIZE"1B"
HDL_POWER"GND"
CDS_LIB"mstr_symbols"
VOLTAGE"0.0V"
BODY_TYPE"PLUMBING";
"A\NAC"18;
%"CAP_A"
"1","(-75,525)","2","dev_discrete","I360";
;
CDS_LOCATION"C3U10"
CDS_SEC"1"
SEC"1"
SEC_TYPE"0402V"
CDS_LIB"dev_discrete"
ROOM"VDDQ_ABC_PWR_VR"
VOLTAGE"16V"
LOCATION"C3U10"
VALUE"0.1UF"
TOLERANCE"10%"
MATERIAL"X7R"
PACK_TYPE"0402V"
PART_NUMBER"A36096-030";
"B"
$PN"2"18;
"A"
$PN"1"62;
END.
